(kicad_pcb
	(version 20260206)
	(generator "pcbnew")
	(generator_version "10.0")
	(general
		(thickness 1.6)
		(legacy_teardrops no)
	)
	(paper "A4")
	(title_block
		(title "fcb — Lightning_FCB_BRD.brd")
		(comment 1 "Lightning (Wiwynn / Facebook NVMe JBOF) / footprints 200-202 of 495")
	)
	(layers
		(0 "F.Cu" signal "TOP")
		(4 "In1.Cu" signal "L2GND")
		(6 "In2.Cu" signal "L3VCC")
		(2 "B.Cu" signal "BOTTOM")
		(9 "F.Adhes" user "F.Adhesive")
		(11 "B.Adhes" user "B.Adhesive")
		(13 "F.Paste" user "Package Geometry/Pastemask Top")
		(15 "B.Paste" user "Package Geometry/Pastemask Bottom")
		(5 "F.SilkS" user "Ref Des/Silkscreen Top")
		(7 "B.SilkS" user "Ref Des/Silkscreen Bottom")
		(1 "F.Mask" user "Board Geometry/Soldermask Top")
		(3 "B.Mask" user "Board Geometry/Soldermask Bottom")
		(17 "Dwgs.User" user "User.Drawings")
		(19 "Cmts.User" user "User.Comments")
		(21 "Eco1.User" user "User.Eco1")
		(23 "Eco2.User" user "User.Eco2")
		(25 "Edge.Cuts" user "Board Geometry/Outline")
		(27 "Margin" user)
		(31 "F.CrtYd" user "Package Geometry/Place Bound Top")
		(29 "B.CrtYd" user "Package Geometry/Place Bound Bottom")
		(35 "F.Fab" user "Ref Des/Assembly Top")
		(33 "B.Fab" user "Ref Des/Assembly Bottom")
	)
	(footprint ""
		(layer "F.Cu")
		(at 34.544 -400.177)
		(property "Reference" "PQ2"
			(at 0 0 0)
			(layer "F.SilkS")
			(hide yes)
			(effects
				(font
					(size 1.27 1.27)
				)
			)
		)
		(property "Value" "PH0925CL-GP"
			(at -4.2799 -0.4572 0)
			(unlocked yes)
			(layer "F.Fab")
			(hide yes)
			(effects
				(font
					(size 1.016 1.016)
					(thickness 0.1524)
				)
			)
		)
		(property "Device Type" "LFPAK-5PH48-U"
			(at -4.2799 -1.9812 0)
			(unlocked yes)
			(layer "F.Fab")
			(hide yes)
			(effects
				(font
					(size 1.016 1.016)
					(thickness 0.1524)
				)
			)
		)
		(duplicate_pad_numbers_are_jumpers no)
		(fp_line
			(start -2.7559 -6.5532)
			(end -2.7559 1.0668)
			(stroke
				(width 0.1524)
				(type default)
			)
			(layer "F.SilkS")
		)
		(fp_line
			(start -2.7559 1.0668)
			(end 2.7559 1.0668)
			(stroke
				(width 0.1524)
				(type default)
			)
			(layer "F.SilkS")
		)
		(fp_line
			(start -1.7272 1.1684)
			(end -2.1082 1.1684)
			(stroke
				(width 0.3302)
				(type default)
			)
			(layer "F.SilkS")
		)
		(fp_line
			(start 2.7559 -6.5532)
			(end -2.7559 -6.5532)
			(stroke
				(width 0.1524)
				(type default)
			)
			(layer "F.SilkS")
		)
		(fp_line
			(start 2.7559 1.0668)
			(end 2.7559 -6.5532)
			(stroke
				(width 0.1524)
				(type default)
			)
			(layer "F.SilkS")
		)
		(fp_poly
			(pts
				(xy -2.3368 1.5748) (xy -1.905 1.143) (xy -1.4732 1.5748)
			)
			(stroke
				(width 0)
				(type default)
			)
			(fill yes)
			(layer "F.SilkS")
		)
		(fp_poly
			(pts
				(xy -2.5019 -4.02971) (xy -0.3302 -4.02971) (xy -0.3302 -6.30301) (xy -2.5019 -6.30301)
			)
			(stroke
				(width 0)
				(type default)
			)
			(fill yes)
			(layer "F.Paste")
		)
		(fp_poly
			(pts
				(xy -2.5019 -1.09601) (xy -0.3302 -1.09601) (xy -0.3302 -3.36931) (xy -2.5019 -3.36931)
			)
			(stroke
				(width 0)
				(type default)
			)
			(fill yes)
			(layer "F.Paste")
		)
		(fp_poly
			(pts
				(xy 0.3302 -4.02971) (xy 2.5019 -4.02971) (xy 2.5019 -6.30301) (xy 0.3302 -6.30301)
			)
			(stroke
				(width 0)
				(type default)
			)
			(fill yes)
			(layer "F.Paste")
		)
		(fp_poly
			(pts
				(xy 0.3302 -1.09601) (xy 2.5019 -1.09601) (xy 2.5019 -3.36931) (xy 0.3302 -3.36931)
			)
			(stroke
				(width 0)
				(type default)
			)
			(fill yes)
			(layer "F.Paste")
		)
		(fp_rect
			(start -2.4511 0.3048)
			(end 2.4511 -5.6896)
			(stroke
				(width 0)
				(type default)
			)
			(fill no)
			(layer "F.CrtYd")
		)
		(fp_poly
			(pts
				(xy -3.0099 1.3208) (xy -3.0099 -6.8072) (xy 3.0099 -6.8072) (xy 3.0099 -1.016) (xy 2.4511 -1.016)
				(xy 2.4511 -5.6896) (xy -2.4511 -5.6896) (xy -2.4511 0.3048) (xy 2.4511 0.3048) (xy 2.4511 -1.0033)
				(xy 3.0099 -1.0033) (xy 3.0099 1.3208)
			)
			(stroke
				(width 0)
				(type default)
			)
			(fill no)
			(layer "F.CrtYd")
		)
		(fp_rect
			(start -3.0099 1.3208)
			(end 3.0099 -6.8072)
			(stroke
				(width 0)
				(type default)
			)
			(fill no)
			(layer "F.Fab")
		)
		(pad "1" smd rect
			(at -1.905 0)
			(size 0.762 1.6256)
			(layers "F.Cu" "F.Mask" "F.Paste")
			(net "P12V")
		)
		(pad "2" smd rect
			(at -0.635 0)
			(size 0.762 1.6256)
			(layers "F.Cu" "F.Mask" "F.Paste")
			(net "P12V")
		)
		(pad "3" smd rect
			(at 0.635 0)
			(size 0.762 1.6256)
			(layers "F.Cu" "F.Mask" "F.Paste")
			(net "P12V")
		)
		(pad "4" smd rect
			(at 1.905 0)
			(size 0.762 1.6256)
			(layers "F.Cu" "F.Mask" "F.Paste")
			(net "ADM1276_GATE_DRV2")
		)
		(pad "5" smd rect
			(at 0 -3.69951)
			(size 5.0038 5.207)
			(layers "F.Cu" "F.Mask" "F.Paste")
			(net "P12V_SENSE_TRACE")
		)
	)
	(footprint ""
		(layer "F.Cu")
		(at 45.499782 -144.999964)
		(property "Reference" "H8"
			(at 0 0 0)
			(layer "F.SilkS")
			(hide yes)
			(effects
				(font
					(size 1.27 1.27)
				)
			)
		)
		(property "Value" "HOLE315R138"
			(at 0 -7.0612 0)
			(unlocked yes)
			(layer "F.Fab")
			(hide yes)
			(effects
				(font
					(size 1.016 1.016)
					(thickness 0.1524)
				)
			)
		)
		(property "Device Type" "HOLE315R138"
			(at 0 -8.5852 0)
			(unlocked yes)
			(layer "F.Fab")
			(hide yes)
			(effects
				(font
					(size 1.016 1.016)
					(thickness 0.1524)
				)
			)
		)
		(duplicate_pad_numbers_are_jumpers no)
		(fp_poly
			(pts
				(xy 0 4.3053) (xy -0.13462 4.30276) (xy -0.27051 4.29641) (xy -0.40513 4.28625) (xy -0.53975 4.27101)
				(xy -0.6731 4.25196) (xy -0.80645 4.2291) (xy -0.9398 4.20116) (xy -1.07061 4.17068) (xy -1.20142 4.13385)
				(xy -1.33096 4.09448) (xy -1.45796 4.0513) (xy -1.58496 4.00304) (xy -1.70942 3.95097) (xy -1.83261 3.89509)
				(xy -1.95453 3.83667) (xy -2.07391 3.77317) (xy -2.19202 3.70586) (xy -2.30632 3.63474) (xy -2.41935 3.56108)
				(xy -2.53111 3.48361) (xy -2.63906 3.40233) (xy -2.74447 3.31724) (xy -2.84734 3.22961) (xy -2.94767 3.13817)
				(xy -3.04419 3.04419) (xy -3.13817 2.94767) (xy -3.22961 2.84734) (xy -3.31724 2.74447) (xy -3.40233 2.63906)
				(xy -3.48361 2.53111) (xy -3.56108 2.41935) (xy -3.63474 2.30632) (xy -3.70586 2.19202) (xy -3.77317 2.07391)
				(xy -3.83667 1.95453) (xy -3.89509 1.83261) (xy -3.95097 1.70942) (xy -4.00304 1.58496) (xy -4.0513 1.45796)
				(xy -4.09448 1.33096) (xy -4.13385 1.20142) (xy -4.17068 1.07061) (xy -4.20116 0.9398) (xy -4.2291 0.80645)
				(xy -4.25196 0.6731) (xy -4.27101 0.53975) (xy -4.28625 0.40513) (xy -4.29641 0.27051) (xy -4.30276 0.13462)
				(xy -4.3053 0) (xy -4.30276 -0.13462) (xy -4.29641 -0.27051) (xy -4.28625 -0.40513) (xy -4.27101 -0.53975)
				(xy -4.25196 -0.6731) (xy -4.2291 -0.80645) (xy -4.20116 -0.9398) (xy -4.17068 -1.07061) (xy -4.13385 -1.20142)
				(xy -4.09448 -1.33096) (xy -4.0513 -1.45796) (xy -4.00304 -1.58496) (xy -3.95097 -1.70942) (xy -3.89509 -1.83261)
				(xy -3.83667 -1.95453) (xy -3.77317 -2.07391) (xy -3.70586 -2.19202) (xy -3.63474 -2.30632) (xy -3.56108 -2.41935)
				(xy -3.48361 -2.53111) (xy -3.40233 -2.63906) (xy -3.31724 -2.74447) (xy -3.22961 -2.84734) (xy -3.13817 -2.94767)
				(xy -3.04419 -3.04419) (xy -2.94767 -3.13817) (xy -2.84734 -3.22961) (xy -2.74447 -3.31724) (xy -2.63906 -3.40233)
				(xy -2.53111 -3.48361) (xy -2.41935 -3.56108) (xy -2.30632 -3.63474) (xy -2.19202 -3.70586) (xy -2.07391 -3.77317)
				(xy -1.95453 -3.83667) (xy -1.83261 -3.89509) (xy -1.70942 -3.95097) (xy -1.58496 -4.00304) (xy -1.45796 -4.0513)
				(xy -1.33096 -4.09448) (xy -1.20142 -4.13385) (xy -1.07061 -4.17068) (xy -0.9398 -4.20116) (xy -0.80645 -4.2291)
				(xy -0.6731 -4.25196) (xy -0.53975 -4.27101) (xy -0.40513 -4.28625) (xy -0.27051 -4.29641) (xy -0.13462 -4.30276)
				(xy 0 -4.3053) (xy 0.13462 -4.30276) (xy 0.27051 -4.29641) (xy 0.40513 -4.28625) (xy 0.53975 -4.27101)
				(xy 0.6731 -4.25196) (xy 0.80645 -4.2291) (xy 0.9398 -4.20116) (xy 1.07061 -4.17068) (xy 1.20142 -4.13385)
				(xy 1.33096 -4.09448) (xy 1.45796 -4.0513) (xy 1.58496 -4.00304) (xy 1.70942 -3.95097) (xy 1.83261 -3.89509)
				(xy 1.95453 -3.83667) (xy 2.07391 -3.77317) (xy 2.19202 -3.70586) (xy 2.30632 -3.63474) (xy 2.41935 -3.56108)
				(xy 2.53111 -3.48361) (xy 2.63906 -3.40233) (xy 2.74447 -3.31724) (xy 2.84734 -3.22961) (xy 2.94767 -3.13817)
				(xy 3.04419 -3.04419) (xy 3.13817 -2.94767) (xy 3.22961 -2.84734) (xy 3.31724 -2.74447) (xy 3.40233 -2.63906)
				(xy 3.48361 -2.53111) (xy 3.56108 -2.41935) (xy 3.63474 -2.30632) (xy 3.70586 -2.19202) (xy 3.77317 -2.07391)
				(xy 3.83667 -1.95453) (xy 3.89509 -1.83261) (xy 3.95097 -1.70942) (xy 4.00304 -1.58496) (xy 4.0513 -1.45796)
				(xy 4.09448 -1.33096) (xy 4.13385 -1.20142) (xy 4.17068 -1.07061) (xy 4.20116 -0.9398) (xy 4.2291 -0.80645)
				(xy 4.25196 -0.6731) (xy 4.27101 -0.53975) (xy 4.28625 -0.40513) (xy 4.29641 -0.27051) (xy 4.30276 -0.13462)
				(xy 4.3053 0) (xy 4.30276 0.13462) (xy 4.29641 0.27051) (xy 4.28625 0.40513) (xy 4.27101 0.53975)
				(xy 4.25196 0.6731) (xy 4.2291 0.80645) (xy 4.20116 0.9398) (xy 4.17068 1.07061) (xy 4.13385 1.20142)
				(xy 4.09448 1.33096) (xy 4.0513 1.45796) (xy 4.00304 1.58496) (xy 3.95097 1.70942) (xy 3.89509 1.83261)
				(xy 3.83667 1.95453) (xy 3.77317 2.07391) (xy 3.70586 2.19202) (xy 3.63474 2.30632) (xy 3.56108 2.41935)
				(xy 3.48361 2.53111) (xy 3.40233 2.63906) (xy 3.31724 2.74447) (xy 3.22961 2.84734) (xy 3.13817 2.94767)
				(xy 3.04419 3.04419) (xy 2.94767 3.13817) (xy 2.84734 3.22961) (xy 2.74447 3.31724) (xy 2.63906 3.40233)
				(xy 2.53111 3.48361) (xy 2.41935 3.56108) (xy 2.30632 3.63474) (xy 2.19202 3.70586) (xy 2.07391 3.77317)
				(xy 1.95453 3.83667) (xy 1.83261 3.89509) (xy 1.70942 3.95097) (xy 1.58496 4.00304) (xy 1.45796 4.0513)
				(xy 1.33096 4.09448) (xy 1.20142 4.13385) (xy 1.07061 4.17068) (xy 0.9398 4.20116) (xy 0.80645 4.2291)
				(xy 0.6731 4.25196) (xy 0.53975 4.27101) (xy 0.40513 4.28625) (xy 0.27051 4.29641) (xy 0.13462 4.30276)
			)
			(stroke
				(width 0)
				(type default)
			)
			(fill no)
			(layer "F.CrtYd")
		)
		(fp_poly
			(pts
				(xy 0 4.3053) (xy -0.13462 4.30276) (xy -0.27051 4.29641) (xy -0.40513 4.28625) (xy -0.53975 4.27101)
				(xy -0.6731 4.25196) (xy -0.80645 4.2291) (xy -0.9398 4.20116) (xy -1.07061 4.17068) (xy -1.20142 4.13385)
				(xy -1.33096 4.09448) (xy -1.45796 4.0513) (xy -1.58496 4.00304) (xy -1.70942 3.95097) (xy -1.83261 3.89509)
				(xy -1.95453 3.83667) (xy -2.07391 3.77317) (xy -2.19202 3.70586) (xy -2.30632 3.63474) (xy -2.41935 3.56108)
				(xy -2.53111 3.48361) (xy -2.63906 3.40233) (xy -2.74447 3.31724) (xy -2.84734 3.22961) (xy -2.94767 3.13817)
				(xy -3.04419 3.04419) (xy -3.13817 2.94767) (xy -3.22961 2.84734) (xy -3.31724 2.74447) (xy -3.40233 2.63906)
				(xy -3.48361 2.53111) (xy -3.56108 2.41935) (xy -3.63474 2.30632) (xy -3.70586 2.19202) (xy -3.77317 2.07391)
				(xy -3.83667 1.95453) (xy -3.89509 1.83261) (xy -3.95097 1.70942) (xy -4.00304 1.58496) (xy -4.0513 1.45796)
				(xy -4.09448 1.33096) (xy -4.13385 1.20142) (xy -4.17068 1.07061) (xy -4.20116 0.9398) (xy -4.2291 0.80645)
				(xy -4.25196 0.6731) (xy -4.27101 0.53975) (xy -4.28625 0.40513) (xy -4.29641 0.27051) (xy -4.30276 0.13462)
				(xy -4.3053 0) (xy -4.30276 -0.13462) (xy -4.29641 -0.27051) (xy -4.28625 -0.40513) (xy -4.27101 -0.53975)
				(xy -4.25196 -0.6731) (xy -4.2291 -0.80645) (xy -4.20116 -0.9398) (xy -4.17068 -1.07061) (xy -4.13385 -1.20142)
				(xy -4.09448 -1.33096) (xy -4.0513 -1.45796) (xy -4.00304 -1.58496) (xy -3.95097 -1.70942) (xy -3.89509 -1.83261)
				(xy -3.83667 -1.95453) (xy -3.77317 -2.07391) (xy -3.70586 -2.19202) (xy -3.63474 -2.30632) (xy -3.56108 -2.41935)
				(xy -3.48361 -2.53111) (xy -3.40233 -2.63906) (xy -3.31724 -2.74447) (xy -3.22961 -2.84734) (xy -3.13817 -2.94767)
				(xy -3.04419 -3.04419) (xy -2.94767 -3.13817) (xy -2.84734 -3.22961) (xy -2.74447 -3.31724) (xy -2.63906 -3.40233)
				(xy -2.53111 -3.48361) (xy -2.41935 -3.56108) (xy -2.30632 -3.63474) (xy -2.19202 -3.70586) (xy -2.07391 -3.77317)
				(xy -1.95453 -3.83667) (xy -1.83261 -3.89509) (xy -1.70942 -3.95097) (xy -1.58496 -4.00304) (xy -1.45796 -4.0513)
				(xy -1.33096 -4.09448) (xy -1.20142 -4.13385) (xy -1.07061 -4.17068) (xy -0.9398 -4.20116) (xy -0.80645 -4.2291)
				(xy -0.6731 -4.25196) (xy -0.53975 -4.27101) (xy -0.40513 -4.28625) (xy -0.27051 -4.29641) (xy -0.13462 -4.30276)
				(xy 0 -4.3053) (xy 0.13462 -4.30276) (xy 0.27051 -4.29641) (xy 0.40513 -4.28625) (xy 0.53975 -4.27101)
				(xy 0.6731 -4.25196) (xy 0.80645 -4.2291) (xy 0.9398 -4.20116) (xy 1.07061 -4.17068) (xy 1.20142 -4.13385)
				(xy 1.33096 -4.09448) (xy 1.45796 -4.0513) (xy 1.58496 -4.00304) (xy 1.70942 -3.95097) (xy 1.83261 -3.89509)
				(xy 1.95453 -3.83667) (xy 2.07391 -3.77317) (xy 2.19202 -3.70586) (xy 2.30632 -3.63474) (xy 2.41935 -3.56108)
				(xy 2.53111 -3.48361) (xy 2.63906 -3.40233) (xy 2.74447 -3.31724) (xy 2.84734 -3.22961) (xy 2.94767 -3.13817)
				(xy 3.04419 -3.04419) (xy 3.13817 -2.94767) (xy 3.22961 -2.84734) (xy 3.31724 -2.74447) (xy 3.40233 -2.63906)
				(xy 3.48361 -2.53111) (xy 3.56108 -2.41935) (xy 3.63474 -2.30632) (xy 3.70586 -2.19202) (xy 3.77317 -2.07391)
				(xy 3.83667 -1.95453) (xy 3.89509 -1.83261) (xy 3.95097 -1.70942) (xy 4.00304 -1.58496) (xy 4.0513 -1.45796)
				(xy 4.09448 -1.33096) (xy 4.13385 -1.20142) (xy 4.17068 -1.07061) (xy 4.20116 -0.9398) (xy 4.2291 -0.80645)
				(xy 4.25196 -0.6731) (xy 4.27101 -0.53975) (xy 4.28625 -0.40513) (xy 4.29641 -0.27051) (xy 4.30276 -0.13462)
				(xy 4.3053 0) (xy 4.30276 0.13462) (xy 4.29641 0.27051) (xy 4.28625 0.40513) (xy 4.27101 0.53975)
				(xy 4.25196 0.6731) (xy 4.2291 0.80645) (xy 4.20116 0.9398) (xy 4.17068 1.07061) (xy 4.13385 1.20142)
				(xy 4.09448 1.33096) (xy 4.0513 1.45796) (xy 4.00304 1.58496) (xy 3.95097 1.70942) (xy 3.89509 1.83261)
				(xy 3.83667 1.95453) (xy 3.77317 2.07391) (xy 3.70586 2.19202) (xy 3.63474 2.30632) (xy 3.56108 2.41935)
				(xy 3.48361 2.53111) (xy 3.40233 2.63906) (xy 3.31724 2.74447) (xy 3.22961 2.84734) (xy 3.13817 2.94767)
				(xy 3.04419 3.04419) (xy 2.94767 3.13817) (xy 2.84734 3.22961) (xy 2.74447 3.31724) (xy 2.63906 3.40233)
				(xy 2.53111 3.48361) (xy 2.41935 3.56108) (xy 2.30632 3.63474) (xy 2.19202 3.70586) (xy 2.07391 3.77317)
				(xy 1.95453 3.83667) (xy 1.83261 3.89509) (xy 1.70942 3.95097) (xy 1.58496 4.00304) (xy 1.45796 4.0513)
				(xy 1.33096 4.09448) (xy 1.20142 4.13385) (xy 1.07061 4.17068) (xy 0.9398 4.20116) (xy 0.80645 4.2291)
				(xy 0.6731 4.25196) (xy 0.53975 4.27101) (xy 0.40513 4.28625) (xy 0.27051 4.29641) (xy 0.13462 4.30276)
			)
			(stroke
				(width 0)
				(type default)
			)
			(fill no)
			(layer "F.Fab")
		)
		(pad "1" thru_hole circle
			(at 0 0)
			(size 8.001 8.001)
			(drill 3.5052)
			(layers "*.Cu" "*.Mask")
			(remove_unused_layers no)
			(net "GND")
			(clearance -1.7399)
			(thermal_gap 0.3048)
			(padstack
				(mode front_inner_back)
				(layer "Inner"
					(shape circle)
					(size 3.9116 3.9116)
					(clearance 0.3048)
				)
				(layer "B.Cu"
					(shape circle)
					(size 8.001 8.001)
					(clearance -1.7399)
				)
			)
		)
	)
	(footprint ""
		(layer "F.Cu")
		(at 21.6408 -290.322 -90)
		(property "Reference" "C44"
			(at 0 0 270)
			(layer "F.SilkS")
			(hide yes)
			(effects
				(font
					(size 1.27 1.27)
				)
			)
		)
		(property "Value" "SCD1U16V2KX-3GP"
			(at 1.1811 -2.7051 270)
			(unlocked yes)
			(layer "F.Fab")
			(hide yes)
			(effects
				(font
					(size 1.016 1.016)
					(thickness 0.1524)
				)
			)
		)
		(property "Device Type" "C402H22"
			(at 1.1811 -4.2291 270)
			(unlocked yes)
			(layer "F.Fab")
			(hide yes)
			(effects
				(font
					(size 1.016 1.016)
					(thickness 0.1524)
				)
			)
		)
		(duplicate_pad_numbers_are_jumpers no)
		(fp_rect
			(start -0.4318 0.9525)
			(end 0.4318 -0.9525)
			(stroke
				(width 0)
				(type default)
			)
			(fill no)
			(layer "F.CrtYd")
		)
		(fp_rect
			(start -0.4318 0.9525)
			(end 0.4318 -0.9525)
			(stroke
				(width 0)
				(type default)
			)
			(fill no)
			(layer "F.Fab")
		)
		(pad "1" smd custom
			(at 0 -0.4445 270)
			(size 0.1524 0.1524)
			(layers "F.Cu" "F.Mask" "F.Paste")
			(net "FAN_TACH4")
			(options
				(clearance outline)
				(anchor circle)
			)
			(primitives
				(gr_poly
					(pts
						(arc
							(start 0.3048 -0.2032)
							(mid 0.275042 -0.275042)
							(end 0.2032 -0.3048)
						)
						(arc
							(start -0.2032 -0.3048)
							(mid -0.275042 -0.275042)
							(end -0.3048 -0.2032)
						)
						(arc
							(start -0.3048 0.2032)
							(mid -0.275042 0.275042)
							(end -0.2032 0.3048)
						)
						(arc
							(start 0.2032 0.3048)
							(mid 0.275042 0.275042)
							(end 0.3048 0.2032)
						)
					)
					(width 0)
					(fill yes)
				)
			)
		)
		(pad "2" smd custom
			(at 0 0.4445 270)
			(size 0.1524 0.1524)
			(layers "F.Cu" "F.Mask" "F.Paste")
			(net "GND")
			(options
				(clearance outline)
				(anchor circle)
			)
			(primitives
				(gr_poly
					(pts
						(arc
							(start 0.3048 -0.2032)
							(mid 0.275042 -0.275042)
							(end 0.2032 -0.3048)
						)
						(arc
							(start -0.2032 -0.3048)
							(mid -0.275042 -0.275042)
							(end -0.3048 -0.2032)
						)
						(arc
							(start -0.3048 0.2032)
							(mid -0.275042 0.275042)
							(end -0.2032 0.3048)
						)
						(arc
							(start 0.2032 0.3048)
							(mid 0.275042 0.275042)
							(end 0.3048 0.2032)
						)
					)
					(width 0)
					(fill yes)
				)
			)
		)
	)
)
